(kicad_pcb
	(version 20260206)
	(generator "pcbnew")
	(generator_version "10.0")
	(general
		(thickness 1.6)
		(legacy_teardrops no)
	)
	(paper "A4")
	(title_block
		(title "12092022_DA0F0TFB6D0_F0T_FAN_BOARD_MP5048_D_brd_v02_OCP.brd")
		(comment 1 "Grand Teton / footprints 262-267 of 924")
	)
	(layers
		(0 "F.Cu" signal "TOP")
		(4 "In1.Cu" signal "GND")
		(6 "In2.Cu" signal "IN1")
		(8 "In3.Cu" signal "IN2")
		(10 "In4.Cu" signal "GND1")
		(2 "B.Cu" signal "BOTTOM")
		(9 "F.Adhes" user "F.Adhesive")
		(11 "B.Adhes" user "B.Adhesive")
		(13 "F.Paste" user "Package Geometry/Pastemask Top")
		(15 "B.Paste" user "Package Geometry/Pastemask Bottom")
		(5 "F.SilkS" user "Ref Des/Silkscreen Top")
		(7 "B.SilkS" user "Ref Des/Silkscreen Bottom")
		(1 "F.Mask" user "Board Geometry/Soldermask Top")
		(3 "B.Mask" user "Board Geometry/Soldermask Bottom")
		(17 "Dwgs.User" user "User.Drawings")
		(19 "Cmts.User" user "User.Comments")
		(21 "Eco1.User" user "User.Eco1")
		(23 "Eco2.User" user "User.Eco2")
		(25 "Edge.Cuts" user "Board Geometry/Outline")
		(27 "Margin" user)
		(31 "F.CrtYd" user "Package Geometry/Place Bound Top")
		(29 "B.CrtYd" user "Package Geometry/Place Bound Bottom")
		(35 "F.Fab" user "Ref Des/Assembly Top")
		(33 "B.Fab" user "Ref Des/Assembly Bottom")
	)
	(footprint ""
		(layer "F.Cu")
		(at 30.988 -36.703 180)
		(property "Reference" "R5653"
			(at 0 0 180)
			(layer "F.SilkS")
			(hide yes)
			(effects
				(font
					(size 1.27 1.27)
				)
			)
		)
		(property "Value" ""
			(at 0 0 180)
			(layer "F.Fab")
			(effects
				(font
					(size 1.27 1.27)
				)
			)
		)
		(duplicate_pad_numbers_are_jumpers no)
		(fp_line
			(start 0.7874 0.4064)
			(end -0.7874 0.4064)
			(stroke
				(width 0.1524)
				(type default)
			)
			(layer "F.SilkS")
		)
		(fp_line
			(start 0.7874 -0.4064)
			(end 0.7874 0.4064)
			(stroke
				(width 0.1524)
				(type default)
			)
			(layer "F.SilkS")
		)
		(fp_line
			(start -0.7874 0.4064)
			(end -0.7874 -0.4064)
			(stroke
				(width 0.1524)
				(type default)
			)
			(layer "F.SilkS")
		)
		(fp_line
			(start -0.7874 -0.4064)
			(end 0.7874 -0.4064)
			(stroke
				(width 0.1524)
				(type default)
			)
			(layer "F.SilkS")
		)
		(fp_line
			(start 0.67945 0.3048)
			(end 0.120396 0.3048)
			(stroke
				(width 0.1)
				(type default)
			)
			(layer "F.Fab")
		)
		(fp_line
			(start 0.67945 -0.3048)
			(end 0.67945 0.3048)
			(stroke
				(width 0.1)
				(type default)
			)
			(layer "F.Fab")
		)
		(fp_line
			(start 0.12065 -0.2794)
			(end 0.12065 -0.3048)
			(stroke
				(width 0.1)
				(type default)
			)
			(layer "F.Fab")
		)
		(fp_line
			(start 0.12065 -0.3048)
			(end 0.67945 -0.3048)
			(stroke
				(width 0.1)
				(type default)
			)
			(layer "F.Fab")
		)
		(fp_line
			(start 0.120396 0.3048)
			(end 0.120396 0.2794)
			(stroke
				(width 0.1)
				(type default)
			)
			(layer "F.Fab")
		)
		(fp_line
			(start 0.120396 0.2794)
			(end -0.12065 0.2794)
			(stroke
				(width 0.1)
				(type default)
			)
			(layer "F.Fab")
		)
		(fp_line
			(start -0.12065 0.3048)
			(end -0.67945 0.3048)
			(stroke
				(width 0.1)
				(type default)
			)
			(layer "F.Fab")
		)
		(fp_line
			(start -0.12065 0.2794)
			(end -0.12065 0.3048)
			(stroke
				(width 0.1)
				(type default)
			)
			(layer "F.Fab")
		)
		(fp_line
			(start -0.12065 -0.2794)
			(end 0.12065 -0.2794)
			(stroke
				(width 0.1)
				(type default)
			)
			(layer "F.Fab")
		)
		(fp_line
			(start -0.12065 -0.305054)
			(end -0.12065 -0.2794)
			(stroke
				(width 0.1)
				(type default)
			)
			(layer "F.Fab")
		)
		(fp_line
			(start -0.67945 0.3048)
			(end -0.67945 -0.305054)
			(stroke
				(width 0.1)
				(type default)
			)
			(layer "F.Fab")
		)
		(fp_line
			(start -0.67945 -0.305054)
			(end -0.12065 -0.305054)
			(stroke
				(width 0.1)
				(type default)
			)
			(layer "F.Fab")
		)
		(pad "1" smd rect
			(at -0.40005 0)
			(size 0.4572 0.508)
			(layers "F.Cu" "F.Mask" "F.Paste")
			(net "P12V_LED")
		)
		(pad "2" smd rect
			(at 0.40005 0)
			(size 0.4572 0.508)
			(layers "F.Cu" "F.Mask" "F.Paste")
			(net "U408_D1")
		)
	)
	(footprint ""
		(layer "F.Cu")
		(at 37.338 -27.391868 180)
		(property "Reference" "R5240"
			(at 0 0 180)
			(layer "F.SilkS")
			(hide yes)
			(effects
				(font
					(size 1.27 1.27)
				)
			)
		)
		(property "Value" ""
			(at 0 0 180)
			(layer "F.Fab")
			(effects
				(font
					(size 1.27 1.27)
				)
			)
		)
		(duplicate_pad_numbers_are_jumpers no)
		(fp_line
			(start 0.7874 0.4064)
			(end -0.7874 0.4064)
			(stroke
				(width 0.1524)
				(type default)
			)
			(layer "F.SilkS")
		)
		(fp_line
			(start 0.7874 -0.4064)
			(end 0.7874 0.4064)
			(stroke
				(width 0.1524)
				(type default)
			)
			(layer "F.SilkS")
		)
		(fp_line
			(start -0.7874 0.4064)
			(end -0.7874 -0.4064)
			(stroke
				(width 0.1524)
				(type default)
			)
			(layer "F.SilkS")
		)
		(fp_line
			(start -0.7874 -0.4064)
			(end 0.7874 -0.4064)
			(stroke
				(width 0.1524)
				(type default)
			)
			(layer "F.SilkS")
		)
		(fp_line
			(start 0.67945 0.3048)
			(end 0.120396 0.3048)
			(stroke
				(width 0.1)
				(type default)
			)
			(layer "F.Fab")
		)
		(fp_line
			(start 0.67945 -0.3048)
			(end 0.67945 0.3048)
			(stroke
				(width 0.1)
				(type default)
			)
			(layer "F.Fab")
		)
		(fp_line
			(start 0.12065 -0.2794)
			(end 0.12065 -0.3048)
			(stroke
				(width 0.1)
				(type default)
			)
			(layer "F.Fab")
		)
		(fp_line
			(start 0.12065 -0.3048)
			(end 0.67945 -0.3048)
			(stroke
				(width 0.1)
				(type default)
			)
			(layer "F.Fab")
		)
		(fp_line
			(start 0.120396 0.3048)
			(end 0.120396 0.2794)
			(stroke
				(width 0.1)
				(type default)
			)
			(layer "F.Fab")
		)
		(fp_line
			(start 0.120396 0.2794)
			(end -0.12065 0.2794)
			(stroke
				(width 0.1)
				(type default)
			)
			(layer "F.Fab")
		)
		(fp_line
			(start -0.12065 0.3048)
			(end -0.67945 0.3048)
			(stroke
				(width 0.1)
				(type default)
			)
			(layer "F.Fab")
		)
		(fp_line
			(start -0.12065 0.2794)
			(end -0.12065 0.3048)
			(stroke
				(width 0.1)
				(type default)
			)
			(layer "F.Fab")
		)
		(fp_line
			(start -0.12065 -0.2794)
			(end 0.12065 -0.2794)
			(stroke
				(width 0.1)
				(type default)
			)
			(layer "F.Fab")
		)
		(fp_line
			(start -0.12065 -0.305054)
			(end -0.12065 -0.2794)
			(stroke
				(width 0.1)
				(type default)
			)
			(layer "F.Fab")
		)
		(fp_line
			(start -0.67945 0.3048)
			(end -0.67945 -0.305054)
			(stroke
				(width 0.1)
				(type default)
			)
			(layer "F.Fab")
		)
		(fp_line
			(start -0.67945 -0.305054)
			(end -0.12065 -0.305054)
			(stroke
				(width 0.1)
				(type default)
			)
			(layer "F.Fab")
		)
		(pad "1" smd circle
			(at -0.40005 0 180)
			(size 0 0)
			(layers "F.Cu" "F.Mask" "F.Paste")
			(net "FAN_3_PWM_IL_R")
		)
		(pad "2" smd circle
			(at 0.40005 0 180)
			(size 0 0)
			(layers "F.Cu" "F.Mask" "F.Paste")
			(net "FAN_3_PWM_IL")
		)
	)
	(footprint ""
		(layer "F.Cu")
		(at 5.461 -247.523 180)
		(property "Reference" "PR65"
			(at 0 0 180)
			(layer "F.SilkS")
			(hide yes)
			(effects
				(font
					(size 1.27 1.27)
				)
			)
		)
		(property "Value" ""
			(at 0 0 180)
			(layer "F.Fab")
			(effects
				(font
					(size 1.27 1.27)
				)
			)
		)
		(duplicate_pad_numbers_are_jumpers no)
		(fp_line
			(start 0.7874 0.4064)
			(end -0.7874 0.4064)
			(stroke
				(width 0.1524)
				(type default)
			)
			(layer "F.SilkS")
		)
		(fp_line
			(start 0.7874 -0.4064)
			(end 0.7874 0.4064)
			(stroke
				(width 0.1524)
				(type default)
			)
			(layer "F.SilkS")
		)
		(fp_line
			(start -0.7874 0.4064)
			(end -0.7874 -0.4064)
			(stroke
				(width 0.1524)
				(type default)
			)
			(layer "F.SilkS")
		)
		(fp_line
			(start -0.7874 -0.4064)
			(end 0.7874 -0.4064)
			(stroke
				(width 0.1524)
				(type default)
			)
			(layer "F.SilkS")
		)
		(fp_line
			(start 0.67945 0.3048)
			(end 0.120396 0.3048)
			(stroke
				(width 0.1)
				(type default)
			)
			(layer "F.Fab")
		)
		(fp_line
			(start 0.67945 -0.3048)
			(end 0.67945 0.3048)
			(stroke
				(width 0.1)
				(type default)
			)
			(layer "F.Fab")
		)
		(fp_line
			(start 0.12065 -0.2794)
			(end 0.12065 -0.3048)
			(stroke
				(width 0.1)
				(type default)
			)
			(layer "F.Fab")
		)
		(fp_line
			(start 0.12065 -0.3048)
			(end 0.67945 -0.3048)
			(stroke
				(width 0.1)
				(type default)
			)
			(layer "F.Fab")
		)
		(fp_line
			(start 0.120396 0.3048)
			(end 0.120396 0.2794)
			(stroke
				(width 0.1)
				(type default)
			)
			(layer "F.Fab")
		)
		(fp_line
			(start 0.120396 0.2794)
			(end -0.12065 0.2794)
			(stroke
				(width 0.1)
				(type default)
			)
			(layer "F.Fab")
		)
		(fp_line
			(start -0.12065 0.3048)
			(end -0.67945 0.3048)
			(stroke
				(width 0.1)
				(type default)
			)
			(layer "F.Fab")
		)
		(fp_line
			(start -0.12065 0.2794)
			(end -0.12065 0.3048)
			(stroke
				(width 0.1)
				(type default)
			)
			(layer "F.Fab")
		)
		(fp_line
			(start -0.12065 -0.2794)
			(end 0.12065 -0.2794)
			(stroke
				(width 0.1)
				(type default)
			)
			(layer "F.Fab")
		)
		(fp_line
			(start -0.12065 -0.305054)
			(end -0.12065 -0.2794)
			(stroke
				(width 0.1)
				(type default)
			)
			(layer "F.Fab")
		)
		(fp_line
			(start -0.67945 0.3048)
			(end -0.67945 -0.305054)
			(stroke
				(width 0.1)
				(type default)
			)
			(layer "F.Fab")
		)
		(fp_line
			(start -0.67945 -0.305054)
			(end -0.12065 -0.305054)
			(stroke
				(width 0.1)
				(type default)
			)
			(layer "F.Fab")
		)
		(pad "1" smd circle
			(at -0.40005 0 180)
			(size 0 0)
			(layers "F.Cu" "F.Mask" "F.Paste")
			(net "FAN_6_P3V_R")
		)
		(pad "2" smd circle
			(at 0.40005 0 180)
			(size 0 0)
			(layers "F.Cu" "F.Mask" "F.Paste")
			(net "FAN_6_MODE")
		)
	)
	(footprint ""
		(layer "F.Cu")
		(at 23.622 -143.891 -90)
		(property "Reference" "R4789"
			(at 0 0 270)
			(layer "F.SilkS")
			(hide yes)
			(effects
				(font
					(size 1.27 1.27)
				)
			)
		)
		(property "Value" ""
			(at 0 0 270)
			(layer "F.Fab")
			(effects
				(font
					(size 1.27 1.27)
				)
			)
		)
		(duplicate_pad_numbers_are_jumpers no)
		(fp_line
			(start -0.7874 0.4064)
			(end -0.7874 -0.4064)
			(stroke
				(width 0.1524)
				(type default)
			)
			(layer "F.SilkS")
		)
		(fp_line
			(start 0.7874 0.4064)
			(end -0.7874 0.4064)
			(stroke
				(width 0.1524)
				(type default)
			)
			(layer "F.SilkS")
		)
		(fp_line
			(start -0.7874 -0.4064)
			(end 0.7874 -0.4064)
			(stroke
				(width 0.1524)
				(type default)
			)
			(layer "F.SilkS")
		)
		(fp_line
			(start 0.7874 -0.4064)
			(end 0.7874 0.4064)
			(stroke
				(width 0.1524)
				(type default)
			)
			(layer "F.SilkS")
		)
		(fp_line
			(start -0.67945 0.3048)
			(end -0.67945 -0.305054)
			(stroke
				(width 0.1)
				(type default)
			)
			(layer "F.Fab")
		)
		(fp_line
			(start -0.12065 0.3048)
			(end -0.67945 0.3048)
			(stroke
				(width 0.1)
				(type default)
			)
			(layer "F.Fab")
		)
		(fp_line
			(start 0.120396 0.3048)
			(end 0.120396 0.2794)
			(stroke
				(width 0.1)
				(type default)
			)
			(layer "F.Fab")
		)
		(fp_line
			(start 0.67945 0.3048)
			(end 0.120396 0.3048)
			(stroke
				(width 0.1)
				(type default)
			)
			(layer "F.Fab")
		)
		(fp_line
			(start -0.12065 0.2794)
			(end -0.12065 0.3048)
			(stroke
				(width 0.1)
				(type default)
			)
			(layer "F.Fab")
		)
		(fp_line
			(start 0.120396 0.2794)
			(end -0.12065 0.2794)
			(stroke
				(width 0.1)
				(type default)
			)
			(layer "F.Fab")
		)
		(fp_line
			(start -0.12065 -0.2794)
			(end 0.12065 -0.2794)
			(stroke
				(width 0.1)
				(type default)
			)
			(layer "F.Fab")
		)
		(fp_line
			(start 0.12065 -0.2794)
			(end 0.12065 -0.3048)
			(stroke
				(width 0.1)
				(type default)
			)
			(layer "F.Fab")
		)
		(fp_line
			(start 0.12065 -0.3048)
			(end 0.67945 -0.3048)
			(stroke
				(width 0.1)
				(type default)
			)
			(layer "F.Fab")
		)
		(fp_line
			(start 0.67945 -0.3048)
			(end 0.67945 0.3048)
			(stroke
				(width 0.1)
				(type default)
			)
			(layer "F.Fab")
		)
		(fp_line
			(start -0.67945 -0.305054)
			(end -0.12065 -0.305054)
			(stroke
				(width 0.1)
				(type default)
			)
			(layer "F.Fab")
		)
		(fp_line
			(start -0.12065 -0.305054)
			(end -0.12065 -0.2794)
			(stroke
				(width 0.1)
				(type default)
			)
			(layer "F.Fab")
		)
		(pad "1" smd circle
			(at -0.40005 0 270)
			(size 0 0)
			(layers "F.Cu" "F.Mask" "F.Paste")
			(net "SMB_FAN0_R_SCL")
		)
		(pad "2" smd circle
			(at 0.40005 0 270)
			(size 0 0)
			(layers "F.Cu" "F.Mask" "F.Paste")
			(net "SMB_FAN0_SCL")
		)
	)
	(footprint ""
		(layer "F.Cu")
		(at 3.81 -183.642)
		(property "Reference" "R2361"
			(at 0 0 0)
			(layer "F.SilkS")
			(hide yes)
			(effects
				(font
					(size 1.27 1.27)
				)
			)
		)
		(property "Value" ""
			(at 0 0 0)
			(layer "F.Fab")
			(effects
				(font
					(size 1.27 1.27)
				)
			)
		)
		(duplicate_pad_numbers_are_jumpers no)
		(fp_line
			(start -0.7874 -0.4064)
			(end 0.7874 -0.4064)
			(stroke
				(width 0.1524)
				(type default)
			)
			(layer "F.SilkS")
		)
		(fp_line
			(start -0.7874 0.4064)
			(end -0.7874 -0.4064)
			(stroke
				(width 0.1524)
				(type default)
			)
			(layer "F.SilkS")
		)
		(fp_line
			(start 0.7874 -0.4064)
			(end 0.7874 0.4064)
			(stroke
				(width 0.1524)
				(type default)
			)
			(layer "F.SilkS")
		)
		(fp_line
			(start 0.7874 0.4064)
			(end -0.7874 0.4064)
			(stroke
				(width 0.1524)
				(type default)
			)
			(layer "F.SilkS")
		)
		(fp_line
			(start -0.67945 -0.305054)
			(end -0.12065 -0.305054)
			(stroke
				(width 0.1)
				(type default)
			)
			(layer "F.Fab")
		)
		(fp_line
			(start -0.67945 0.3048)
			(end -0.67945 -0.305054)
			(stroke
				(width 0.1)
				(type default)
			)
			(layer "F.Fab")
		)
		(fp_line
			(start -0.12065 -0.305054)
			(end -0.12065 -0.2794)
			(stroke
				(width 0.1)
				(type default)
			)
			(layer "F.Fab")
		)
		(fp_line
			(start -0.12065 -0.2794)
			(end 0.12065 -0.2794)
			(stroke
				(width 0.1)
				(type default)
			)
			(layer "F.Fab")
		)
		(fp_line
			(start -0.12065 0.2794)
			(end -0.12065 0.3048)
			(stroke
				(width 0.1)
				(type default)
			)
			(layer "F.Fab")
		)
		(fp_line
			(start -0.12065 0.3048)
			(end -0.67945 0.3048)
			(stroke
				(width 0.1)
				(type default)
			)
			(layer "F.Fab")
		)
		(fp_line
			(start 0.120396 0.2794)
			(end -0.12065 0.2794)
			(stroke
				(width 0.1)
				(type default)
			)
			(layer "F.Fab")
		)
		(fp_line
			(start 0.120396 0.3048)
			(end 0.120396 0.2794)
			(stroke
				(width 0.1)
				(type default)
			)
			(layer "F.Fab")
		)
		(fp_line
			(start 0.12065 -0.3048)
			(end 0.67945 -0.3048)
			(stroke
				(width 0.1)
				(type default)
			)
			(layer "F.Fab")
		)
		(fp_line
			(start 0.12065 -0.2794)
			(end 0.12065 -0.3048)
			(stroke
				(width 0.1)
				(type default)
			)
			(layer "F.Fab")
		)
		(fp_line
			(start 0.67945 -0.3048)
			(end 0.67945 0.3048)
			(stroke
				(width 0.1)
				(type default)
			)
			(layer "F.Fab")
		)
		(fp_line
			(start 0.67945 0.3048)
			(end 0.120396 0.3048)
			(stroke
				(width 0.1)
				(type default)
			)
			(layer "F.Fab")
		)
		(pad "1" smd circle
			(at -0.40005 0)
			(size 0 0)
			(layers "F.Cu" "F.Mask" "F.Paste")
			(net "P3V3_AUX")
		)
		(pad "2" smd circle
			(at 0.40005 0)
			(size 0 0)
			(layers "F.Cu" "F.Mask" "F.Paste")
			(net "PCA9555_MB0_A1")
		)
	)
	(footprint ""
		(layer "F.Cu")
		(at 35.56 -32.217868 180)
		(property "Reference" "C2052"
			(at 0 0 180)
			(layer "F.SilkS")
			(hide yes)
			(effects
				(font
					(size 1.27 1.27)
				)
			)
		)
		(property "Value" ""
			(at 0 0 180)
			(layer "F.Fab")
			(effects
				(font
					(size 1.27 1.27)
				)
			)
		)
		(duplicate_pad_numbers_are_jumpers no)
		(fp_line
			(start 0.7874 0.4064)
			(end -0.7874 0.4064)
			(stroke
				(width 0.1524)
				(type default)
			)
			(layer "F.SilkS")
		)
		(fp_line
			(start 0.7874 -0.4064)
			(end 0.7874 0.4064)
			(stroke
				(width 0.1524)
				(type default)
			)
			(layer "F.SilkS")
		)
		(fp_line
			(start -0.7874 0.4064)
			(end -0.7874 -0.4064)
			(stroke
				(width 0.1524)
				(type default)
			)
			(layer "F.SilkS")
		)
		(fp_line
			(start -0.7874 -0.4064)
			(end 0.7874 -0.4064)
			(stroke
				(width 0.1524)
				(type default)
			)
			(layer "F.SilkS")
		)
		(fp_line
			(start 0.67945 0.3048)
			(end 0.120396 0.3048)
			(stroke
				(width 0.1)
				(type default)
			)
			(layer "F.Fab")
		)
		(fp_line
			(start 0.67945 -0.3048)
			(end 0.67945 0.3048)
			(stroke
				(width 0.1)
				(type default)
			)
			(layer "F.Fab")
		)
		(fp_line
			(start 0.12065 -0.2794)
			(end 0.12065 -0.3048)
			(stroke
				(width 0.1)
				(type default)
			)
			(layer "F.Fab")
		)
		(fp_line
			(start 0.12065 -0.3048)
			(end 0.67945 -0.3048)
			(stroke
				(width 0.1)
				(type default)
			)
			(layer "F.Fab")
		)
		(fp_line
			(start 0.120396 0.3048)
			(end 0.120396 0.2794)
			(stroke
				(width 0.1)
				(type default)
			)
			(layer "F.Fab")
		)
		(fp_line
			(start 0.120396 0.2794)
			(end -0.12065 0.2794)
			(stroke
				(width 0.1)
				(type default)
			)
			(layer "F.Fab")
		)
		(fp_line
			(start -0.12065 0.3048)
			(end -0.67945 0.3048)
			(stroke
				(width 0.1)
				(type default)
			)
			(layer "F.Fab")
		)
		(fp_line
			(start -0.12065 0.2794)
			(end -0.12065 0.3048)
			(stroke
				(width 0.1)
				(type default)
			)
			(layer "F.Fab")
		)
		(fp_line
			(start -0.12065 -0.2794)
			(end 0.12065 -0.2794)
			(stroke
				(width 0.1)
				(type default)
			)
			(layer "F.Fab")
		)
		(fp_line
			(start -0.12065 -0.305054)
			(end -0.12065 -0.2794)
			(stroke
				(width 0.1)
				(type default)
			)
			(layer "F.Fab")
		)
		(fp_line
			(start -0.67945 0.3048)
			(end -0.67945 -0.305054)
			(stroke
				(width 0.1)
				(type default)
			)
			(layer "F.Fab")
		)
		(fp_line
			(start -0.67945 -0.305054)
			(end -0.12065 -0.305054)
			(stroke
				(width 0.1)
				(type default)
			)
			(layer "F.Fab")
		)
		(pad "1" smd circle
			(at -0.40005 0 180)
			(size 0 0)
			(layers "F.Cu" "F.Mask" "F.Paste")
			(net "FAN_3_PWM_OL_R")
		)
		(pad "2" smd circle
			(at 0.40005 0 180)
			(size 0 0)
			(layers "F.Cu" "F.Mask" "F.Paste")
			(net "GND")
		)
	)
)
